# S9S_MB_2U (Grand Teton) — schematic netlist excerpt (pin names and nets, part order shuffled) for the footprints in the layout excerpt that follows; sources: Cadence DE-HDL packaged netlist, KiCad conversion of 03242023_DA0F0TMBIJ0_F0T_Motherboard_J_brd_V01_OCP.brd

U271  LM75BD  IC  pkg SO8_1-27_4-9X3-9  page 170
  SDA  = SMB_LM75_1_3V3AUX_SDA_R1
  SCL  = SMB_LM75_1_3V3AUX_SCL_R1
  OS  = FM_G751_1_ALERT_N
  GND  = GND
  A2  = U271_1_ADD2
  A1  = U271_1_ADD1
  A0  = U271_1_ADD0
  VCC  = P3V3_AUX

R3529  Q_RES  10K 1% CHIP  pkg 0402LF  page 194 : A = P3V3_AUX ; B = SMB_PCIE_E1S_ISO_EN_R

(kicad_pcb
	(version 20260206)
	(generator "pcbnew")
	(generator_version "10.0")
	(general
		(thickness 1.6)
		(legacy_teardrops no)
	)
	(paper "A4")
	(title_block
		(title "03242023_DA0F0TMBIJ0_F0T_Motherboard_J_brd_V01_OCP.brd")
		(comment 1 "Grand Teton / footprints 1130-1131 of 6105")
	)
	(layers
		(0 "F.Cu" signal "TOP")
		(4 "In1.Cu" signal "GND")
		(6 "In2.Cu" signal "IN1")
		(8 "In3.Cu" signal "GND1")
		(10 "In4.Cu" signal "IN2")
		(12 "In5.Cu" signal "GND2")
		(14 "In6.Cu" signal "IN3")
		(16 "In7.Cu" signal "GND3")
		(18 "In8.Cu" signal "VCC")
		(20 "In9.Cu" signal "VCC1")
		(22 "In10.Cu" signal "GND4")
		(24 "In11.Cu" signal "IN4")
		(26 "In12.Cu" signal "GND5")
		(28 "In13.Cu" signal "IN5")
		(30 "In14.Cu" signal "GND6")
		(32 "In15.Cu" signal "IN6")
		(34 "In16.Cu" signal "GND7")
		(2 "B.Cu" signal "BOTTOM")
		(9 "F.Adhes" user "F.Adhesive")
		(11 "B.Adhes" user "B.Adhesive")
		(13 "F.Paste" user "Package Geometry/Pastemask Top")
		(15 "B.Paste" user "Package Geometry/Pastemask Bottom")
		(5 "F.SilkS" user "Ref Des/Silkscreen Top")
		(7 "B.SilkS" user "Ref Des/Silkscreen Bottom")
		(1 "F.Mask" user "Board Geometry/Soldermask Top")
		(3 "B.Mask" user "Board Geometry/Soldermask Bottom")
		(17 "Dwgs.User" user "User.Drawings")
		(19 "Cmts.User" user "User.Comments")
		(21 "Eco1.User" user "User.Eco1")
		(23 "Eco2.User" user "User.Eco2")
		(25 "Edge.Cuts" user "Board Geometry/Outline")
		(27 "Margin" user)
		(31 "F.CrtYd" user "Package Geometry/Place Bound Top")
		(29 "B.CrtYd" user "Package Geometry/Place Bound Bottom")
		(35 "F.Fab" user "Ref Des/Assembly Top")
		(33 "B.Fab" user "Ref Des/Assembly Bottom")
	)
	(footprint ""
		(layer "F.Cu")
		(at 291.83203 -15.348204)
		(property "Reference" "U271"
			(at -3.98018 -3.442208 0)
			(unlocked yes)
			(layer "F.SilkS")
			(effects
				(font
					(size 0.7874 0.5842)
					(thickness 0.1524)
				)
				(justify left)
			)
		)
		(property "Value" ""
			(at 0 0 0)
			(layer "F.Fab")
			(effects
				(font
					(size 1.27 1.27)
				)
			)
		)
		(duplicate_pad_numbers_are_jumpers no)
		(fp_line
			(start -3.447796 -2.500122)
			(end -3.447796 2.500122)
			(stroke
				(width 0.1524)
				(type default)
			)
			(layer "F.SilkS")
		)
		(fp_line
			(start -3.447796 2.500122)
			(end 3.447796 2.500122)
			(stroke
				(width 0.1524)
				(type default)
			)
			(layer "F.SilkS")
		)
		(fp_line
			(start -1.484122 -2.500122)
			(end -3.447796 -2.500122)
			(stroke
				(width 0.1524)
				(type default)
			)
			(layer "F.SilkS")
		)
		(fp_line
			(start 0 -1.016)
			(end -1.484122 -2.500122)
			(stroke
				(width 0.1524)
				(type default)
			)
			(layer "F.SilkS")
		)
		(fp_line
			(start 1.484122 -2.500122)
			(end 0 -1.016)
			(stroke
				(width 0.1524)
				(type default)
			)
			(layer "F.SilkS")
		)
		(fp_line
			(start 3.447796 -2.500122)
			(end 1.484122 -2.500122)
			(stroke
				(width 0.1524)
				(type default)
			)
			(layer "F.SilkS")
		)
		(fp_line
			(start 3.447796 2.500122)
			(end 3.447796 -2.500122)
			(stroke
				(width 0.1524)
				(type default)
			)
			(layer "F.SilkS")
		)
		(fp_poly
			(pts
				(xy -4.5974 -2.413) (xy -3.5814 -1.905) (xy -4.5974 -1.397)
			)
			(stroke
				(width 0)
				(type default)
			)
			(fill yes)
			(layer "F.SilkS")
		)
		(fp_line
			(start -1.999996 -2.500122)
			(end -1.999996 2.500122)
			(stroke
				(width 0.1)
				(type default)
			)
			(layer "F.Fab")
		)
		(fp_line
			(start -1.999996 2.500122)
			(end 1.999996 2.500122)
			(stroke
				(width 0.1)
				(type default)
			)
			(layer "F.Fab")
		)
		(fp_line
			(start 1.999996 -2.500122)
			(end -1.999996 -2.500122)
			(stroke
				(width 0.1)
				(type default)
			)
			(layer "F.Fab")
		)
		(fp_line
			(start 1.999996 2.500122)
			(end 1.999996 -2.500122)
			(stroke
				(width 0.1)
				(type default)
			)
			(layer "F.Fab")
		)
		(fp_poly
			(pts
				(xy -4.5974 -2.413) (xy -4.5974 -1.397) (xy -3.5814 -1.905)
			)
			(stroke
				(width 0)
				(type default)
			)
			(fill yes)
			(layer "F.Fab")
		)
		(pad "1" smd rect
			(at -2.649982 -1.905 270)
			(size 0.6096 1.3208)
			(layers "F.Cu" "F.Mask" "F.Paste")
			(net "SMB_LM75_1_3V3AUX_SDA_R1")
		)
		(pad "2" smd rect
			(at -2.649982 -0.635 270)
			(size 0.6096 1.3208)
			(layers "F.Cu" "F.Mask" "F.Paste")
			(net "SMB_LM75_1_3V3AUX_SCL_R1")
		)
		(pad "3" smd rect
			(at -2.649982 0.635 270)
			(size 0.6096 1.3208)
			(layers "F.Cu" "F.Mask" "F.Paste")
			(net "FM_G751_1_ALERT_N")
		)
		(pad "4" smd rect
			(at -2.649982 1.905 270)
			(size 0.6096 1.3208)
			(layers "F.Cu" "F.Mask" "F.Paste")
			(net "GND")
		)
		(pad "5" smd rect
			(at 2.649982 1.905 270)
			(size 0.6096 1.3208)
			(layers "F.Cu" "F.Mask" "F.Paste")
			(net "U271_1_ADD2")
		)
		(pad "6" smd rect
			(at 2.649982 0.635 270)
			(size 0.6096 1.3208)
			(layers "F.Cu" "F.Mask" "F.Paste")
			(net "U271_1_ADD1")
		)
		(pad "7" smd rect
			(at 2.649982 -0.635 270)
			(size 0.6096 1.3208)
			(layers "F.Cu" "F.Mask" "F.Paste")
			(net "U271_1_ADD0")
		)
		(pad "8" smd rect
			(at 2.649982 -1.905 270)
			(size 0.6096 1.3208)
			(layers "F.Cu" "F.Mask" "F.Paste")
			(net "P3V3_AUX")
		)
	)
	(footprint ""
		(layer "F.Cu")
		(at 210.74888 -42.382948)
		(property "Reference" "R3529"
			(at 0 0 0)
			(layer "F.SilkS")
			(hide yes)
			(effects
				(font
					(size 1.27 1.27)
				)
			)
		)
		(property "Value" ""
			(at 0 0 0)
			(layer "F.Fab")
			(effects
				(font
					(size 1.27 1.27)
				)
			)
		)
		(duplicate_pad_numbers_are_jumpers no)
		(fp_line
			(start -0.7874 -0.4064)
			(end 0.7874 -0.4064)
			(stroke
				(width 0.1524)
				(type default)
			)
			(layer "F.SilkS")
		)
		(fp_line
			(start -0.7874 0.4064)
			(end -0.7874 -0.4064)
			(stroke
				(width 0.1524)
				(type default)
			)
			(layer "F.SilkS")
		)
		(fp_line
			(start 0.7874 -0.4064)
			(end 0.7874 0.4064)
			(stroke
				(width 0.1524)
				(type default)
			)
			(layer "F.SilkS")
		)
		(fp_line
			(start 0.7874 0.4064)
			(end -0.7874 0.4064)
			(stroke
				(width 0.1524)
				(type default)
			)
			(layer "F.SilkS")
		)
		(fp_line
			(start -0.67945 -0.305054)
			(end -0.12065 -0.305054)
			(stroke
				(width 0.1)
				(type default)
			)
			(layer "F.Fab")
		)
		(fp_line
			(start -0.67945 0.3048)
			(end -0.67945 -0.305054)
			(stroke
				(width 0.1)
				(type default)
			)
			(layer "F.Fab")
		)
		(fp_line
			(start -0.12065 -0.305054)
			(end -0.12065 -0.2794)
			(stroke
				(width 0.1)
				(type default)
			)
			(layer "F.Fab")
		)
		(fp_line
			(start -0.12065 -0.2794)
			(end 0.12065 -0.2794)
			(stroke
				(width 0.1)
				(type default)
			)
			(layer "F.Fab")
		)
		(fp_line
			(start -0.12065 0.2794)
			(end -0.12065 0.3048)
			(stroke
				(width 0.1)
				(type default)
			)
			(layer "F.Fab")
		)
		(fp_line
			(start -0.12065 0.3048)
			(end -0.67945 0.3048)
			(stroke
				(width 0.1)
				(type default)
			)
			(layer "F.Fab")
		)
		(fp_line
			(start 0.120396 0.2794)
			(end -0.12065 0.2794)
			(stroke
				(width 0.1)
				(type default)
			)
			(layer "F.Fab")
		)
		(fp_line
			(start 0.120396 0.3048)
			(end 0.120396 0.2794)
			(stroke
				(width 0.1)
				(type default)
			)
			(layer "F.Fab")
		)
		(fp_line
			(start 0.12065 -0.3048)
			(end 0.67945 -0.3048)
			(stroke
				(width 0.1)
				(type default)
			)
			(layer "F.Fab")
		)
		(fp_line
			(start 0.12065 -0.2794)
			(end 0.12065 -0.3048)
			(stroke
				(width 0.1)
				(type default)
			)
			(layer "F.Fab")
		)
		(fp_line
			(start 0.67945 -0.3048)
			(end 0.67945 0.3048)
			(stroke
				(width 0.1)
				(type default)
			)
			(layer "F.Fab")
		)
		(fp_line
			(start 0.67945 0.3048)
			(end 0.120396 0.3048)
			(stroke
				(width 0.1)
				(type default)
			)
			(layer "F.Fab")
		)
		(pad "1" smd circle
			(at -0.40005 0)
			(size 0 0)
			(layers "F.Cu" "F.Mask" "F.Paste")
			(net "P3V3_AUX")
		)
		(pad "2" smd circle
			(at 0.40005 0)
			(size 0 0)
			(layers "F.Cu" "F.Mask" "F.Paste")
			(net "SMB_PCIE_E1S_ISO_EN_R")
		)
	)
)
